FILE_TYPE = CONNECTIVITY;
{Allegro Design Entry HDL 17.4-2019 S026 (4007227) 1/17/2022}
"PAGE_NUMBER" = 84;
0"NC";
1"GND\g";
2"GND\g";
3"GND\g";
4"GND\g";
5"GND\g";
6"P3V3_AUX\g";
7"P3V3_AUX\g";
8"GND\g";
9"GND\g";
10"GND\g";
11"P5V_AUX_VCC\g";
12"GND\g";
13"P3V3_AUX\g";
14"GND\g";
15"P3V3_AUX\g";
16"P3V3_AUX\g";
17"GND\g";
18"GND\g";
19"P3V3_AUX\g";
20"RST_PERST_CPU1_SWB_1_N";
21"RST_PERST_CPU0_SWB_N";
22"PWRGD_P3V3_AUX";
23"LED_HDD_ACTIVITY_B_N";
24"FM_THERMAL_ALERT_N";
25"RST_PERST_CPU1_SWB_N";
26"RST_PERST_CPU0_SWB_R_N";
27"FM_SMB_RST_E1S_0_R_N";
28"RST_PERST_CPU1_SWB_1_R_N";
29"SCM_SYS_PWROK_R1";
30"RST_PERST_CPU1_SWB_R_N";
31"PWRGD_P3V3_AUX_PDB";
32"SCM_SYS_PWROK_R2";
33"SCM_SYS_PWROK_R";
34"JTAG_SCM_PLD_TMS";
35"JTAG_PLD_TMS";
36"JTAG_SCM_PLD_TDI";
37"JTAG_PLD_TDI";
38"JTAG_PLD_TDO";
39"JTAG_SCM_PLD_TCK";
40"JTAG_PLD_TCK";
41"FM_SMB_RST_E1S_0_N";
42"PWRGD_CPU1_PWROK";
43"PWRGD_CPU0_PWROK";
44"RST_CPU1_RESETL_N";
45"RST_CPU0_RESETL_N";
46"BMC_FPGA_LED2_N";
47"BMC_FPGA_LED1_N";
48"P3V3_AUX\g";
49"BMC_FPGA_LED2";
50"BMC_FPGA_LED2_R_N";
51"BMC_FPGA_LED1";
52"BMC_FPGA_LED1_R_N";
53"PWRGD_P5V_AUX_R1";
54"PWRGD_P5V_AUX_R2";
55"PWRGD_P5V_AUX_R3";
56"PWRGD_P5V_AUX";
57"LED_HDD_ACTIVITY_B_PLD_N";
58"FM_THERMAL_ALERT_R_N";
59"JTAG_SCM_PLD_TDO";
60"IRQ_HSC_FAULT";
61"IRQ_HSC_FAULT_BUF_N";
62"IRQ_HSC_FAULT_N";
63"GND\g";
%"Q_CAP"
"1","(-925,3625)","0","pure_quanta","I101";
;
LOCATION"C8005"
$SEC"1"
CDS_SEC"1"
VALUE"0.1UF"
VOLTAGE"25V"
TOLERANCE"10%"
MATERIAL"X7R"
PACK_TYPE"0402"
CDS_LIB"pure_quanta"
PART_NUMBER"CH4104K1B00";
"B"
$PN"2"1;
"A"
$PN"1"55;
%"UNIVERSAL_GND"
"1","(-925,3300)","0","pure_quanta_power","I102";
;
CDS_LIB"pure_quanta_power"
HDL_POWER"GND";
"A"1;
%"Q_RES"
"1","(-1275,3850)","2","pure_quanta","I103";
;
LOCATION"R6118"
$SEC"1"
CDS_SEC"1"
VALUE"0"
PACK_TYPE"0402LF"
TOLERANCE"5%"
MATERIAL"CHIP"
WATTAGE"1/16W"
CDS_LIB"pure_quanta"
BOM_COST"MEM"
PART_NUMBER"CS00002JB13";
"B"
$PN"2"54;
"A"
$PN"1"55;
%"Q_RES"
"2","(-8650,6275)","2","pure_quanta","I104";
;
LOCATION"R1422"
$SEC"1"
CDS_SEC"1"
VALUE"100"
TOLERANCE"1%"
PACK_TYPE"0402LF"
WATTAGE"1/16W"
MATERIAL"CHIP"
CDS_LIB"pure_quanta"
PART_NUMBER"CS11002FB07";
"A"
$PN"1"43;
"B"
$PN"2"42;
%"UNIVERSAL_GND"
"1","(-8625,3375)","0","pure_quanta_power","I105";
;
CDS_LIB"pure_quanta_power"
HDL_POWER"GND";
"A"2;
%"Q_RES"
"2","(-8625,3650)","0","pure_quanta","I106";
;
LOCATION"R9025"
$SEC"1"
CDS_SEC"1"
MATERIAL"EMPTY"
PACK_TYPE"0402LF"
TOLERANCE"1%"
WATTAGE"1/16W"
VALUE"100K"
CDS_LIB"pure_quanta"
PART_NUMBER"CS41002FB09";
"A"
$PN"1"62;
"B"
$PN"2"2;
%"UNIVERSAL_GND"
"1","(-7475,3525)","0","pure_quanta_power","I110";
;
CDS_LIB"pure_quanta_power"
HDL_POWER"GND";
"A"3;
%"MOSFET_NCH_DUAL"
"1","(-7525,3900)","0","pure_quanta","I111";
;
LOCATION"Q9003"
$SEC"1"
CDS_SEC"1"
PART_TYPE"SMLF"
VALUE"PJT138K"
MATERIAL"IC"
NEEDS_NO_SIZE"TRUE"
CDS_LMAN_SYM_OUTLINE"-150,150,150,-150"
CDS_LIB"pure_quanta"
PART_NUMBER"BAM138K0003";
"D1"
$PN"6"60;
"G1"
$PN"2"62;
"S1"
$PN"1"3;
%"Q_RES"
"2","(-7475,4500)","0","pure_quanta","I112";
;
LOCATION"R9026"
$SEC"1"
CDS_SEC"1"
PACK_TYPE"0402LF"
TOLERANCE"5%"
WATTAGE"1/16W"
MATERIAL"CHIP"
VALUE"4.7K"
CDS_LIB"pure_quanta"
PART_NUMBER"CS24702JB10";
"A"
$PN"1"6;
"B"
$PN"2"60;
%"UNIVERSAL_GND"
"1","(-6325,3825)","0","pure_quanta_power","I113";
;
CDS_LIB"pure_quanta_power"
HDL_POWER"GND";
"A"4;
%"Q_RES"
"2","(-6325,4625)","0","pure_quanta","I114";
;
LOCATION"R9027"
$SEC"1"
CDS_SEC"1"
MATERIAL"CHIP"
WATTAGE"1/16W"
TOLERANCE"1%"
VALUE"100K"
PACK_TYPE"0402LF"
CDS_LIB"pure_quanta"
PART_NUMBER"CS41002FB09";
"A"
$PN"1"7;
"B"
$PN"2"61;
%"UNIVERSAL_GND"
"1","(-5550,3950)","0","pure_quanta_power","I115";
;
CDS_LIB"pure_quanta_power"
HDL_POWER"GND";
"A"5;
%"Q_CAP"
"1","(-5550,4150)","0","pure_quanta","I116";
;
LOCATION"C9005"
$SEC"1"
CDS_SEC"1"
VOLTAGE"25V"
VALUE"0.1UF"
PACK_TYPE"0402"
TOLERANCE"10%"
MATERIAL"X7R"
CDS_LIB"pure_quanta"
PART_NUMBER"CH4104K1B00";
"B"
$PN"2"5;
"A"
$PN"1"61;
%"Q_RES"
"1","(-7075,5075)","0","pure_quanta","I118";
;
LOCATION"R9028"
$SEC"1"
CDS_SEC"1"
VALUE"0"
TOLERANCE"5%"
MATERIAL"EMPTY"
WATTAGE"1/16W"
PACK_TYPE"0402LF"
CDS_LIB"pure_quanta"
PART_NUMBER"CS00002JB13";
"B"
$PN"2"61;
"A"
$PN"1"62;
%"UNIVERSAL_POWER"
"1","(-7475,4725)","0","pure_quanta_power","I119";
;
HDL_POWER"P3V3_AUX"
CDS_LIB"pure_quanta_power";
"A"6;
%"UNIVERSAL_POWER"
"1","(-6325,4850)","0","pure_quanta_power","I120";
;
HDL_POWER"P3V3_AUX"
CDS_LIB"pure_quanta_power";
"A"7;
%"MOSFET_NCH_DUAL"
"2","(-6375,4200)","0","pure_quanta","I121";
;
LOCATION"Q9003"
$SEC"2"
CDS_SEC"2"
VALUE"PJT138K"
PART_TYPE"SMLF"
MATERIAL"IC"
NEEDS_NO_SIZE"TRUE"
CDS_LMAN_SYM_OUTLINE"-150,150,150,-150"
CDS_LIB"pure_quanta"
PART_NUMBER"BAM138K0003";
"S2"
$PN"4"4;
"G2"
$PN"5"60;
"D2"
$PN"3"61;
%"Q_RES"
"2","(-6525,6300)","2","pure_quanta","I27";
;
LOCATION"R530"
$SEC"1"
CDS_SEC"1"
PACK_TYPE"0402LF"
VALUE"0"
MATERIAL"CHIP"
TOLERANCE"5%"
WATTAGE"1/16W"
CDS_LIB"pure_quanta"
PART_NUMBER"CS00002JB13";
"A"
$PN"1"45;
"B"
$PN"2"44;
%"UNIVERSAL_POWER"
"1","(-3925,6300)","0","pure_quanta_power","I30";
;
HDL_POWER"P3V3_AUX"
BOM_COST"OCP3.0 "
CDS_LIB"pure_quanta_power";
"A"48;
%"Q_RES"
"1","(-2575,1525)","2","pure_quanta","I35";
;
LOCATION"R15"
$SEC"1"
CDS_SEC"1"
VALUE"0"
PACK_TYPE"0402LF"
TOLERANCE"5%"
MATERIAL"CHIP"
WATTAGE"1/16W"
BOM_COST"MEM"
CDS_LIB"pure_quanta"
PART_NUMBER"CS00002JB13";
"B"
$PN"2"39;
"A"
$PN"1"40;
%"Q_RES"
"1","(-2575,1625)","2","pure_quanta","I36";
;
LOCATION"R14"
$SEC"1"
CDS_SEC"1"
VALUE"0"
PACK_TYPE"0402LF"
TOLERANCE"5%"
MATERIAL"CHIP"
WATTAGE"1/16W"
CDS_LIB"pure_quanta"
BOM_COST"MEM"
PART_NUMBER"CS00002JB13";
"B"
$PN"2"34;
"A"
$PN"1"35;
%"Q_RES"
"1","(-2575,1825)","2","pure_quanta","I37";
;
LOCATION"R9"
$SEC"1"
CDS_SEC"1"
VALUE"0"
PACK_TYPE"0402LF"
TOLERANCE"5%"
MATERIAL"CHIP"
WATTAGE"1/16W"
CDS_LIB"pure_quanta"
BOM_COST"MEM"
PART_NUMBER"CS00002JB13";
"B"
$PN"2"36;
"A"
$PN"1"37;
%"Q_RES"
"1","(-2575,1775)","2","pure_quanta","I38";
;
LOCATION"R13"
$SEC"1"
CDS_SEC"1"
VALUE"0"
PACK_TYPE"0402LF"
TOLERANCE"5%"
MATERIAL"CHIP"
WATTAGE"1/16W"
CDS_LIB"pure_quanta"
BOM_COST"MEM"
PART_NUMBER"CS00002JB13";
"B"
$PN"2"59;
"A"
$PN"1"38;
%"UNIVERSAL_GND"
"1","(-1750,1400)","0","pure_quanta_power","I39";
;
CDS_LIB"pure_quanta_power"
HDL_POWER"GND";
"A"8;
%"UNIVERSAL_GND"
"1","(-1850,1925)","0","pure_quanta_power","I40";
;
CDS_LIB"pure_quanta_power"
HDL_POWER"GND";
"A"63;
%"CONN8_HBB1081L200D8H"
"1","(-1475,1700)","0","pure_quanta","I41";
;
LOCATION"J57"
$SEC"1"
CDS_SEC"1"
VALUE"CONN8_HBB1081-L200D-8H"
MATERIAL"IO"
PART_TYPE"THLF"
CDS_LIB"pure_quanta"
NEEDS_NO_SIZE"TRUE"
CDS_LMAN_SYM_OUTLINE"-50,225,50,-225"
PART_NUMBER"DFHD08MS197";
"8"
$PN"8"40;
"7"
$PN"7"8;
"6"
$PN"6"35;
"5"
$PN"5"0;
"4"
$PN"4"0;
"3"
$PN"3"38;
"2"
$PN"2"37;
"1"
$PN"1"19;
%"Q_CAP"
"1","(-1850,2075)","0","pure_quanta","I42";
;
LOCATION"C20"
$SEC"1"
CDS_SEC"1"
PACK_TYPE"C0402"
VOLTAGE"16V"
VALUE"0.1UF"
TOLERANCE"10%"
MATERIAL"X7R"
CDS_LIB"pure_quanta"
PART_NUMBER"CH4103K1B08";
"B"
$PN"2"63;
"A"
$PN"1"19;
%"UNIVERSAL_POWER"
"1","(-1725,2375)","2","pure_quanta_power","I43";
;
HDL_POWER"P3V3_AUX"
CDS_LIB"pure_quanta_power";
"A"19;
%"Q_RES"
"1","(-3700,5700)","0","pure_quanta","I45";
;
LOCATION"R1266"
$SEC"1"
CDS_SEC"1"
PACK_TYPE"0402LF"
WATTAGE"1/16W"
MATERIAL"CHIP"
TOLERANCE"1%"
VALUE"200"
CDS_LIB"pure_quanta"
PART_NUMBER"CS12002FB06";
"B"
$PN"2"52;
"A"
$PN"1"48;
%"Q_RES"
"1","(-3700,6050)","0","pure_quanta","I46";
;
LOCATION"R1194"
$SEC"1"
CDS_SEC"1"
WATTAGE"1/16W"
MATERIAL"CHIP"
TOLERANCE"1%"
VALUE"200"
PACK_TYPE"0402LF"
CDS_LIB"pure_quanta"
PART_NUMBER"CS12002FB06";
"B"
$PN"2"50;
"A"
$PN"1"48;
%"UNIVERSAL_GND"
"1","(-2050,5175)","0","pure_quanta_power","I47";
;
HDL_POWER"GND"
BOM_COST"MISC."
CDS_LIB"pure_quanta_power";
"A"9;
%"MOSFET_DUAL_6P"
"1","(-1675,5350)","6","pure_quanta","I48";
;
LOCATION"Q28"
$SEC"1"
CDS_SEC"1"
PART_TYPE"SMLF"
MATERIAL"IC"
VALUE"2N7002KDW"
CDS_LIB"pure_quanta"
CDS_LMAN_SYM_OUTLINE"-150,100,150,-100"
NEEDS_NO_SIZE"TRUE"
PART_NUMBER"BAM70020047";
"D2"
$PN"3"46;
"D1"
$PN"6"47;
"S2"
$PN"4"10;
"S1"
$PN"1"9;
"G2"
$PN"5"49;
"G1"
$PN"2"51;
%"Q_RES"
"1","(-7625,1700)","0","pure_quanta","I5";
;
LOCATION"R1303"
$SEC"1"
CDS_SEC"1"
VALUE"1K"
CDS_LIB"pure_quanta"
PACK_TYPE"0402LF"
MATERIAL"CHIP"
WATTAGE"1/16W"
TOLERANCE"1%"
PART_NUMBER"CS21002FB06";
"B"
$PN"2"15;
"A"
$PN"1"41;
%"UNIVERSAL_GND"
"1","(-1275,5175)","0","pure_quanta_power","I51";
;
HDL_POWER"GND"
BOM_COST"MISC."
CDS_LIB"pure_quanta_power";
"A"10;
%"Q_RES"
"1","(-7550,1550)","0","pure_quanta","I53";
;
LOCATION"R6074"
$SEC"1"
CDS_SEC"1"
VALUE"0"
PACK_TYPE"0402LF"
TOLERANCE"5%"
MATERIAL"CHIP"
WATTAGE"1/16W"
BOM_COST"MEM"
CDS_LIB"pure_quanta"
PART_NUMBER"CS00002JB13";
"B"
$PN"2"58;
"A"
$PN"1"24;
%"Q_RES"
"1","(-7550,1425)","0","pure_quanta","I57";
;
LOCATION"R6075"
$SEC"1"
CDS_SEC"1"
VALUE"0"
PACK_TYPE"0402LF"
TOLERANCE"5%"
MATERIAL"CHIP"
WATTAGE"1/16W"
BOM_COST"MEM"
CDS_LIB"pure_quanta"
PART_NUMBER"CS00002JB13";
"B"
$PN"2"57;
"A"
$PN"1"23;
%"Q_RES"
"1","(-7625,1925)","0","pure_quanta","I6";
;
LOCATION"R1036"
$SEC"1"
CDS_SEC"1"
VALUE"0"
MATERIAL"CHIP"
CDS_LIB"pure_quanta"
BOM_COST"OCP3.0 "
WATTAGE"1/16W"
TOLERANCE"5%"
PACK_TYPE"0402LF"
PART_NUMBER"CS00002JB13";
"B"
$PN"2"27;
"A"
$PN"1"41;
%"Q_RES"
"1","(-7550,1300)","0","pure_quanta","I61";
;
LOCATION"R6078"
$SEC"1"
CDS_SEC"1"
VALUE"0"
PACK_TYPE"0402LF"
TOLERANCE"5%"
MATERIAL"CHIP"
WATTAGE"1/16W"
BOM_COST"MEM"
CDS_LIB"pure_quanta"
PART_NUMBER"CS00002JB13";
"B"
$PN"2"31;
"A"
$PN"1"22;
%"Q_RES"
"2","(-4225,3900)","0","pure_quanta","I63";
;
LOCATION"R2343"
$SEC"1"
CDS_SEC"1"
PACK_TYPE"0402LF"
VALUE"10K"
TOLERANCE"1%"
WATTAGE"1/16W"
MATERIAL"EMPTY"
CDS_LIB"pure_quanta"
PART_NUMBER"CS31002FB08";
"A"
$PN"1"11;
"B"
$PN"2"56;
%"UNIVERSAL_POWER"
"1","(-4225,4150)","0","pure_quanta_power","I64";
;
HDL_POWER"P5V_AUX_VCC"
CDS_LIB"pure_quanta_power";
"A"11;
%"MOSFET_NCH_DUAL"
"1","(-3300,3575)","0","pure_quanta","I65";
;
LOCATION"Q50"
$SEC"1"
CDS_SEC"1"
PART_TYPE"SMLF"
MATERIAL"IC"
VALUE"PJT138K"
CDS_LIB"pure_quanta"
CDS_LMAN_SYM_OUTLINE"-150,150,150,-150"
NEEDS_NO_SIZE"TRUE"
PART_NUMBER"BAM138K0003";
"D1"
$PN"6"53;
"G1"
$PN"2"56;
"S1"
$PN"1"12;
%"UNIVERSAL_GND"
"1","(-3250,3275)","0","pure_quanta_power","I66";
;
CDS_LIB"pure_quanta_power"
HDL_POWER"GND";
"A"12;
%"Q_RES"
"2","(-3250,4100)","0","pure_quanta","I67";
;
LOCATION"R2344"
$SEC"1"
CDS_SEC"1"
PACK_TYPE"0402LF"
VALUE"4.7K"
TOLERANCE"5%"
MATERIAL"CHIP"
WATTAGE"1/16W"
CDS_LIB"pure_quanta"
PART_NUMBER"CS24702JB10";
"A"
$PN"1"13;
"B"
$PN"2"53;
%"UNIVERSAL_POWER"
"1","(-3250,4350)","0","pure_quanta_power","I68";
;
HDL_POWER"P3V3_AUX"
CDS_LIB"pure_quanta_power";
"A"13;
%"UNIVERSAL_GND"
"1","(-2100,3275)","0","pure_quanta_power","I69";
;
CDS_LIB"pure_quanta_power"
HDL_POWER"GND";
"A"14;
%"VCC_CORE"
"1","(-7200,1700)","5","pure_quanta_power","I7";
;
HDL_POWER"P3V3_AUX"
CDS_LIB"pure_quanta_power";
"A"15;
%"Q_RES"
"2","(-2100,4100)","0","pure_quanta","I70";
;
LOCATION"R2346"
$SEC"1"
CDS_SEC"1"
TOLERANCE"1%"
VALUE"100K"
WATTAGE"1/16W"
MATERIAL"CHIP"
PACK_TYPE"0402LF"
CDS_LIB"pure_quanta"
PART_NUMBER"CS41002FB09";
"A"
$PN"1"16;
"B"
$PN"2"54;
%"UNIVERSAL_POWER"
"1","(-2100,4350)","0","pure_quanta_power","I71";
;
HDL_POWER"P3V3_AUX"
CDS_LIB"pure_quanta_power";
"A"16;
%"MOSFET_NCH_DUAL"
"2","(-2150,3575)","0","pure_quanta","I73";
;
LOCATION"Q50"
$SEC"2"
CDS_SEC"2"
VALUE"PJT138K"
PART_TYPE"SMLF"
MATERIAL"IC"
CDS_LIB"pure_quanta"
CDS_LMAN_SYM_OUTLINE"-150,150,150,-150"
NEEDS_NO_SIZE"TRUE"
PART_NUMBER"BAM138K0003";
"S2"
$PN"4"14;
"G2"
$PN"5"53;
"D2"
$PN"3"54;
%"Q_RES"
"1","(-7550,1000)","0","pure_quanta","I75";
;
LOCATION"R6113"
$SEC"1"
CDS_SEC"1"
VALUE"33.2"
BOM_COST"MEM"
WATTAGE"1/16W"
MATERIAL"CHIP"
PACK_TYPE"0402LF"
TOLERANCE"1%"
CDS_LIB"pure_quanta"
PART_NUMBER"CS03322FB03";
"B"
$PN"2"30;
"A"
$PN"1"25;
%"Q_RES"
"2","(-2950,1225)","0","pure_quanta","I77";
;
LOCATION"R6090"
$SEC"1"
CDS_SEC"1"
MATERIAL"CHIP"
PACK_TYPE"0402LF"
VALUE"4.7K"
TOLERANCE"5%"
WATTAGE"1/16W"
CDS_LIB"pure_quanta"
PART_NUMBER"CS24702JB10";
"A"
$PN"1"39;
"B"
$PN"2"17;
%"UNIVERSAL_GND"
"1","(-2950,950)","0","pure_quanta_power","I78";
;
CDS_LIB"pure_quanta_power"
HDL_POWER"GND";
"A"17;
%"Q_RES"
"1","(-7550,875)","0","pure_quanta","I82";
;
LOCATION"R6092"
$SEC"1"
CDS_SEC"1"
VALUE"0"
CDS_LIB"pure_quanta"
BOM_COST"MEM"
WATTAGE"1/16W"
MATERIAL"CHIP"
TOLERANCE"5%"
PACK_TYPE"0402LF"
PART_NUMBER"CS00002JB13";
"B"
$PN"2"29;
"A"
$PN"1"33;
%"Q_RES"
"1","(-7550,775)","0","pure_quanta","I84";
;
LOCATION"R6093"
$SEC"1"
CDS_SEC"1"
VALUE"0"
PACK_TYPE"0402LF"
TOLERANCE"5%"
MATERIAL"CHIP"
WATTAGE"1/16W"
BOM_COST"MEM"
CDS_LIB"pure_quanta"
PART_NUMBER"CS00002JB13";
"B"
$PN"2"32;
"A"
$PN"1"33;
%"Q_CAP"
"1","(-7150,550)","0","pure_quanta","I88";
;
LOCATION"C1209"
$SEC"1"
CDS_SEC"1"
PACK_TYPE"0402"
MATERIAL"NPO"
TOLERANCE"5%"
VOLTAGE"50V"
VALUE"100PF"
CDS_LIB"pure_quanta"
PART_NUMBER"CH11006JB00";
"B"
$PN"2"18;
"A"
$PN"1"32;
%"UNIVERSAL_GND"
"1","(-7150,275)","0","pure_quanta_power","I89";
;
CDS_LIB"pure_quanta_power"
HDL_POWER"GND";
"A"18;
%"Q_RES"
"1","(-7550,1150)","0","pure_quanta","I91";
;
LOCATION"R6112"
$SEC"1"
CDS_SEC"1"
VALUE"33.2"
CDS_LIB"pure_quanta"
BOM_COST"MEM"
WATTAGE"1/16W"
MATERIAL"CHIP"
PACK_TYPE"0402LF"
TOLERANCE"1%"
PART_NUMBER"CS03322FB03";
"B"
$PN"2"26;
"A"
$PN"1"21;
%"Q_RES"
"1","(-7550,2100)","0","pure_quanta","I94";
;
LOCATION"R2"
$SEC"1"
CDS_SEC"1"
VALUE"33.2"
CDS_LIB"pure_quanta"
TOLERANCE"1%"
PACK_TYPE"0402LF"
MATERIAL"CHIP"
WATTAGE"1/16W"
BOM_COST"MEM"
PART_NUMBER"CS03322FB03";
"B"
$PN"2"28;
"A"
$PN"1"20;
%"Q_LED"
"1","(-2550,6050)","0","pure_quanta","I96";
;
LOCATION"D7"
$SEC"1"
CDS_SEC"1"
COLOR"LED_YELLOW"
MANUF_PN"LTST-C190KSKT-P"
PACK_TYPE"SMLF"
MATERIAL"IC"
CDS_LIB"pure_quanta"
NEEDS_NO_SIZE"TRUE"
PART_NUMBER"BEYL0159Z00";
"A"
$PN"A"50;
"C"
$PN"C"46;
%"Q_LED"
"1","(-2525,5700)","0","pure_quanta","I97";
;
LOCATION"D8"
$SEC"1"
CDS_SEC"1"
COLOR"LED_YELLOW"
MATERIAL"IC"
MANUF_PN"LTST-C190KSKT-P"
PACK_TYPE"SMLF"
CDS_LIB"pure_quanta"
NEEDS_NO_SIZE"TRUE"
PART_NUMBER"BEYL0159Z00";
"A"
$PN"A"52;
"C"
$PN"C"47;
END.
